# T6G (Grand Teton) — schematic netlist excerpt (pin names and nets, part order shuffled) for the footprints in the layout excerpt that follows; sources: Cadence DE-HDL packaged netlist, KiCad conversion of 04192023_DAF0TMB3IC0_F0TG_MB_C_brd_V02_OCP.brd

U90  PI6CV304LE  IC  pkg TSSOP8  page 133
  CLK_IN  = CLK_50M_RMII_R
  OE  = CLK_50M_EN
  Y0  = CLK_50M_BMC_MAC_R
  GND  = GND
  Y1  = CLK_50M_NCSI_OCP_1
  VDD  = P3V3_AUX
  Y2  = CLK_50M_NCSI_OCP_2
  Y3  = TP_CLK_50M_Y3

(kicad_pcb
	(version 20260206)
	(generator "pcbnew")
	(generator_version "10.0")
	(general
		(thickness 1.6)
		(legacy_teardrops no)
	)
	(paper "A4")
	(title_block
		(title "04192023_DAF0TMB3IC0_F0TG_MB_C_brd_V02_OCP.brd")
		(comment 1 "Grand Teton / footprints 3912-3912 of 8354")
	)
	(layers
		(0 "F.Cu" signal "TOP")
		(4 "In1.Cu" signal "GND")
		(6 "In2.Cu" signal "IN1")
		(8 "In3.Cu" signal "GND1")
		(10 "In4.Cu" signal "IN2")
		(12 "In5.Cu" signal "GND2")
		(14 "In6.Cu" signal "IN3")
		(16 "In7.Cu" signal "GND3")
		(18 "In8.Cu" signal "VCC")
		(20 "In9.Cu" signal "VCC1")
		(22 "In10.Cu" signal "GND4")
		(24 "In11.Cu" signal "IN4")
		(26 "In12.Cu" signal "GND5")
		(28 "In13.Cu" signal "IN5")
		(30 "In14.Cu" signal "GND6")
		(32 "In15.Cu" signal "IN6")
		(34 "In16.Cu" signal "GND7")
		(2 "B.Cu" signal "BOTTOM")
		(9 "F.Adhes" user "F.Adhesive")
		(11 "B.Adhes" user "B.Adhesive")
		(13 "F.Paste" user "Package Geometry/Pastemask Top")
		(15 "B.Paste" user "Package Geometry/Pastemask Bottom")
		(5 "F.SilkS" user "Ref Des/Silkscreen Top")
		(7 "B.SilkS" user "Ref Des/Silkscreen Bottom")
		(1 "F.Mask" user "Board Geometry/Soldermask Top")
		(3 "B.Mask" user "Board Geometry/Soldermask Bottom")
		(17 "Dwgs.User" user "User.Drawings")
		(19 "Cmts.User" user "User.Comments")
		(21 "Eco1.User" user "User.Eco1")
		(23 "Eco2.User" user "User.Eco2")
		(25 "Edge.Cuts" user "Board Geometry/Outline")
		(27 "Margin" user)
		(31 "F.CrtYd" user "Package Geometry/Place Bound Top")
		(29 "B.CrtYd" user "Package Geometry/Place Bound Bottom")
		(35 "F.Fab" user "Ref Des/Assembly Top")
		(33 "B.Fab" user "Ref Des/Assembly Bottom")
	)
	(footprint ""
		(layer "F.Cu")
		(at 214.344504 -17.766792 -90)
		(property "Reference" "U90"
			(at -0.832612 -2.35331 90)
			(unlocked yes)
			(layer "F.SilkS")
			(effects
				(font
					(size 0.7874 0.5842)
					(thickness 0.1524)
				)
				(justify left)
			)
		)
		(property "Value" ""
			(at 0 0 270)
			(layer "F.Fab")
			(effects
				(font
					(size 1.27 1.27)
				)
			)
		)
		(duplicate_pad_numbers_are_jumpers no)
		(fp_line
			(start -2.25044 1.5494)
			(end -2.25044 1.3208)
			(stroke
				(width 0.1524)
				(type default)
			)
			(layer "F.SilkS")
		)
		(fp_line
			(start 2.25044 1.5494)
			(end -2.25044 1.5494)
			(stroke
				(width 0.1524)
				(type default)
			)
			(layer "F.SilkS")
		)
		(fp_line
			(start 2.25044 1.3208)
			(end 2.25044 1.5494)
			(stroke
				(width 0.1524)
				(type default)
			)
			(layer "F.SilkS")
		)
		(fp_line
			(start 0 -0.9652)
			(end -0.5842 -1.5494)
			(stroke
				(width 0.1524)
				(type default)
			)
			(layer "F.SilkS")
		)
		(fp_line
			(start 2.25044 -1.3208)
			(end 2.25044 -1.5494)
			(stroke
				(width 0.1524)
				(type default)
			)
			(layer "F.SilkS")
		)
		(fp_line
			(start -2.25044 -1.5494)
			(end -2.25044 -1.3208)
			(stroke
				(width 0.1524)
				(type default)
			)
			(layer "F.SilkS")
		)
		(fp_line
			(start -0.5842 -1.5494)
			(end -2.25044 -1.5494)
			(stroke
				(width 0.1524)
				(type default)
			)
			(layer "F.SilkS")
		)
		(fp_line
			(start 0.5842 -1.5494)
			(end 0 -0.9652)
			(stroke
				(width 0.1524)
				(type default)
			)
			(layer "F.SilkS")
		)
		(fp_line
			(start 2.0066 -1.5494)
			(end 0.5842 -1.5494)
			(stroke
				(width 0.1524)
				(type default)
			)
			(layer "F.SilkS")
		)
		(fp_line
			(start 2.25044 -1.5494)
			(end 0.5842 -1.5494)
			(stroke
				(width 0.1524)
				(type default)
			)
			(layer "F.SilkS")
		)
		(fp_poly
			(pts
				(xy -3.81 -1.016) (xy -4.36372 -0.719328) (xy -4.36372 -1.344168)
			)
			(stroke
				(width 0)
				(type default)
			)
			(fill yes)
			(layer "F.SilkS")
		)
		(fp_line
			(start -2.25044 1.5494)
			(end 2.25044 1.5494)
			(stroke
				(width 0.1)
				(type default)
			)
			(layer "F.Fab")
		)
		(fp_line
			(start -2.25044 1.5494)
			(end -2.25044 1.12522)
			(stroke
				(width 0.1)
				(type default)
			)
			(layer "F.Fab")
		)
		(fp_line
			(start 2.25044 1.5494)
			(end 2.25044 1.12522)
			(stroke
				(width 0.1)
				(type default)
			)
			(layer "F.Fab")
		)
		(fp_line
			(start 2.25044 1.5494)
			(end 2.25044 -1.5494)
			(stroke
				(width 0.1)
				(type default)
			)
			(layer "F.Fab")
		)
		(fp_line
			(start 2.25044 1.143)
			(end 2.25044 1.0922)
			(stroke
				(width 0.1)
				(type default)
			)
			(layer "F.Fab")
		)
		(fp_line
			(start -3.302 1.12522)
			(end -3.302 -1.12522)
			(stroke
				(width 0.1)
				(type default)
			)
			(layer "F.Fab")
		)
		(fp_line
			(start -2.25044 1.12522)
			(end -3.302 1.12522)
			(stroke
				(width 0.1)
				(type default)
			)
			(layer "F.Fab")
		)
		(fp_line
			(start 2.25044 1.12522)
			(end 3.302 1.12522)
			(stroke
				(width 0.1)
				(type default)
			)
			(layer "F.Fab")
		)
		(fp_line
			(start 3.302 1.12522)
			(end 3.302 -1.12522)
			(stroke
				(width 0.1)
				(type default)
			)
			(layer "F.Fab")
		)
		(fp_line
			(start -3.302 -1.12522)
			(end -2.25044 -1.12522)
			(stroke
				(width 0.1)
				(type default)
			)
			(layer "F.Fab")
		)
		(fp_line
			(start -2.25044 -1.12522)
			(end -2.25044 -1.5494)
			(stroke
				(width 0.1)
				(type default)
			)
			(layer "F.Fab")
		)
		(fp_line
			(start 2.25044 -1.12522)
			(end 2.25044 -1.4986)
			(stroke
				(width 0.1)
				(type default)
			)
			(layer "F.Fab")
		)
		(fp_line
			(start 3.302 -1.12522)
			(end 2.25044 -1.12522)
			(stroke
				(width 0.1)
				(type default)
			)
			(layer "F.Fab")
		)
		(fp_line
			(start -2.25044 -1.5494)
			(end -2.25044 1.5494)
			(stroke
				(width 0.1)
				(type default)
			)
			(layer "F.Fab")
		)
		(fp_line
			(start 2.25044 -1.5494)
			(end -2.25044 -1.5494)
			(stroke
				(width 0.1)
				(type default)
			)
			(layer "F.Fab")
		)
		(fp_poly
			(pts
				(xy -4.36372 -0.719328) (xy -4.36372 -1.344168) (xy -3.81 -1.016)
			)
			(stroke
				(width 0)
				(type default)
			)
			(fill yes)
			(layer "F.Fab")
		)
		(pad "1" smd rect
			(at -2.921 -0.975106 180)
			(size 0.3556 1.4986)
			(layers "F.Cu" "F.Mask" "F.Paste")
			(net "CLK_50M_RMII_R")
		)
		(pad "2" smd rect
			(at -2.921 -0.32512 180)
			(size 0.3556 1.4986)
			(layers "F.Cu" "F.Mask" "F.Paste")
			(net "CLK_50M_EN")
		)
		(pad "3" smd rect
			(at -2.921 0.32512 180)
			(size 0.3556 1.4986)
			(layers "F.Cu" "F.Mask" "F.Paste")
			(net "CLK_50M_BMC_MAC_R")
		)
		(pad "4" smd rect
			(at -2.921 0.975106 180)
			(size 0.3556 1.4986)
			(layers "F.Cu" "F.Mask" "F.Paste")
			(net "GND")
		)
		(pad "5" smd rect
			(at 2.921 0.975106 180)
			(size 0.3556 1.4986)
			(layers "F.Cu" "F.Mask" "F.Paste")
			(net "CLK_50M_NCSI_OCP_1")
		)
		(pad "6" smd rect
			(at 2.921 0.32512 180)
			(size 0.3556 1.4986)
			(layers "F.Cu" "F.Mask" "F.Paste")
			(net "P3V3_AUX")
		)
		(pad "7" smd rect
			(at 2.921 -0.32512 180)
			(size 0.3556 1.4986)
			(layers "F.Cu" "F.Mask" "F.Paste")
			(net "CLK_50M_NCSI_OCP_2")
		)
		(pad "8" smd rect
			(at 2.921 -0.975106 180)
			(size 0.3556 1.4986)
			(layers "F.Cu" "F.Mask" "F.Paste")
			(net "TP_CLK_50M_Y3")
		)
	)
)
